(kicad_pcb
	(version 20260206)
	(generator "pcbnew")
	(generator_version "10.0")
	(general
		(thickness 1.6)
		(legacy_teardrops no)
	)
	(paper "A4")
	(title_block
		(title "04192023_DAF0TMB3IC0_F0TG_MB_C_brd_V02_OCP.brd")
		(comment 1 "Grand Teton / footprints 7677-7683 of 8354")
	)
	(layers
		(0 "F.Cu" signal "TOP")
		(4 "In1.Cu" signal "GND")
		(6 "In2.Cu" signal "IN1")
		(8 "In3.Cu" signal "GND1")
		(10 "In4.Cu" signal "IN2")
		(12 "In5.Cu" signal "GND2")
		(14 "In6.Cu" signal "IN3")
		(16 "In7.Cu" signal "GND3")
		(18 "In8.Cu" signal "VCC")
		(20 "In9.Cu" signal "VCC1")
		(22 "In10.Cu" signal "GND4")
		(24 "In11.Cu" signal "IN4")
		(26 "In12.Cu" signal "GND5")
		(28 "In13.Cu" signal "IN5")
		(30 "In14.Cu" signal "GND6")
		(32 "In15.Cu" signal "IN6")
		(34 "In16.Cu" signal "GND7")
		(2 "B.Cu" signal "BOTTOM")
		(9 "F.Adhes" user "F.Adhesive")
		(11 "B.Adhes" user "B.Adhesive")
		(13 "F.Paste" user "Package Geometry/Pastemask Top")
		(15 "B.Paste" user "Package Geometry/Pastemask Bottom")
		(5 "F.SilkS" user "Ref Des/Silkscreen Top")
		(7 "B.SilkS" user "Ref Des/Silkscreen Bottom")
		(1 "F.Mask" user "Board Geometry/Soldermask Top")
		(3 "B.Mask" user "Board Geometry/Soldermask Bottom")
		(17 "Dwgs.User" user "User.Drawings")
		(19 "Cmts.User" user "User.Comments")
		(21 "Eco1.User" user "User.Eco1")
		(23 "Eco2.User" user "User.Eco2")
		(25 "Edge.Cuts" user "Board Geometry/Outline")
		(27 "Margin" user)
		(31 "F.CrtYd" user "Package Geometry/Place Bound Top")
		(29 "B.CrtYd" user "Package Geometry/Place Bound Bottom")
		(35 "F.Fab" user "Ref Des/Assembly Top")
		(33 "B.Fab" user "Ref Des/Assembly Bottom")
	)
	(footprint ""
		(layer "B.Cu")
		(at 110.039404 -28.70327 -90)
		(property "Reference" "C6104"
			(at 0 0 90)
			(layer "B.SilkS")
			(hide yes)
			(effects
				(font
					(size 1.27 1.27)
				)
				(justify mirror)
			)
		)
		(property "Value" ""
			(at 0 0 90)
			(layer "B.Fab")
			(effects
				(font
					(size 1.27 1.27)
				)
				(justify mirror)
			)
		)
		(duplicate_pad_numbers_are_jumpers no)
		(fp_line
			(start -0.7874 0.4064)
			(end 0.7874 0.4064)
			(stroke
				(width 0.1524)
				(type default)
			)
			(layer "B.SilkS")
		)
		(fp_line
			(start 0.7874 0.4064)
			(end 0.7874 -0.4064)
			(stroke
				(width 0.1524)
				(type default)
			)
			(layer "B.SilkS")
		)
		(fp_line
			(start -0.7874 -0.4064)
			(end -0.7874 0.4064)
			(stroke
				(width 0.1524)
				(type default)
			)
			(layer "B.SilkS")
		)
		(fp_line
			(start 0.7874 -0.4064)
			(end -0.7874 -0.4064)
			(stroke
				(width 0.1524)
				(type default)
			)
			(layer "B.SilkS")
		)
		(fp_line
			(start -0.67945 0.3048)
			(end -0.120396 0.3048)
			(stroke
				(width 0.1)
				(type default)
			)
			(layer "B.Fab")
		)
		(fp_line
			(start -0.120396 0.3048)
			(end -0.120396 0.2794)
			(stroke
				(width 0.1)
				(type default)
			)
			(layer "B.Fab")
		)
		(fp_line
			(start 0.12065 0.3048)
			(end 0.67945 0.3048)
			(stroke
				(width 0.1)
				(type default)
			)
			(layer "B.Fab")
		)
		(fp_line
			(start 0.67945 0.3048)
			(end 0.67945 -0.305054)
			(stroke
				(width 0.1)
				(type default)
			)
			(layer "B.Fab")
		)
		(fp_line
			(start -0.120396 0.2794)
			(end 0.12065 0.2794)
			(stroke
				(width 0.1)
				(type default)
			)
			(layer "B.Fab")
		)
		(fp_line
			(start 0.12065 0.2794)
			(end 0.12065 0.3048)
			(stroke
				(width 0.1)
				(type default)
			)
			(layer "B.Fab")
		)
		(fp_line
			(start -0.12065 -0.2794)
			(end -0.12065 -0.3048)
			(stroke
				(width 0.1)
				(type default)
			)
			(layer "B.Fab")
		)
		(fp_line
			(start 0.12065 -0.2794)
			(end -0.12065 -0.2794)
			(stroke
				(width 0.1)
				(type default)
			)
			(layer "B.Fab")
		)
		(fp_line
			(start -0.67945 -0.3048)
			(end -0.67945 0.3048)
			(stroke
				(width 0.1)
				(type default)
			)
			(layer "B.Fab")
		)
		(fp_line
			(start -0.12065 -0.3048)
			(end -0.67945 -0.3048)
			(stroke
				(width 0.1)
				(type default)
			)
			(layer "B.Fab")
		)
		(fp_line
			(start 0.12065 -0.305054)
			(end 0.12065 -0.2794)
			(stroke
				(width 0.1)
				(type default)
			)
			(layer "B.Fab")
		)
		(fp_line
			(start 0.67945 -0.305054)
			(end 0.12065 -0.305054)
			(stroke
				(width 0.1)
				(type default)
			)
			(layer "B.Fab")
		)
		(pad "1" smd circle
			(at 0.40005 0 90)
			(size 0 0)
			(layers "B.Cu" "B.Mask" "B.Paste")
			(net "P3V3_AUX_CPU0_USB2_AVDD33")
		)
		(pad "2" smd circle
			(at -0.40005 0 90)
			(size 0 0)
			(layers "B.Cu" "B.Mask" "B.Paste")
			(net "GND")
		)
	)
	(footprint ""
		(layer "B.Cu")
		(at 303.268126 -192.660016 180)
		(property "Reference" "C142"
			(at 0 0 0)
			(layer "B.SilkS")
			(hide yes)
			(effects
				(font
					(size 1.27 1.27)
				)
				(justify mirror)
			)
		)
		(property "Value" ""
			(at 0 0 0)
			(layer "B.Fab")
			(effects
				(font
					(size 1.27 1.27)
				)
				(justify mirror)
			)
		)
		(duplicate_pad_numbers_are_jumpers no)
		(fp_line
			(start 1.524 0.762)
			(end 1.524 -0.762)
			(stroke
				(width 0.1524)
				(type default)
			)
			(layer "B.SilkS")
		)
		(fp_line
			(start 1.524 -0.762)
			(end -1.524 -0.762)
			(stroke
				(width 0.1524)
				(type default)
			)
			(layer "B.SilkS")
		)
		(fp_line
			(start -1.524 0.762)
			(end 1.524 0.762)
			(stroke
				(width 0.1524)
				(type default)
			)
			(layer "B.SilkS")
		)
		(fp_line
			(start -1.524 -0.762)
			(end -1.524 0.762)
			(stroke
				(width 0.1524)
				(type default)
			)
			(layer "B.SilkS")
		)
		(fp_line
			(start 1.1049 0.724916)
			(end -1.1049 0.724916)
			(stroke
				(width 0.1)
				(type default)
			)
			(layer "B.Fab")
		)
		(fp_line
			(start 1.1049 -0.724916)
			(end 1.1049 0.724916)
			(stroke
				(width 0.1)
				(type default)
			)
			(layer "B.Fab")
		)
		(fp_line
			(start -1.1049 0.724916)
			(end -1.1049 -0.724916)
			(stroke
				(width 0.1)
				(type default)
			)
			(layer "B.Fab")
		)
		(fp_line
			(start -1.1049 -0.724916)
			(end 1.1049 -0.724916)
			(stroke
				(width 0.1)
				(type default)
			)
			(layer "B.Fab")
		)
		(pad "1" smd rect
			(at 0.889 0 180)
			(size 1.016 1.27)
			(layers "B.Cu" "B.Mask" "B.Paste")
			(net "P12V_MEM_CPU0")
		)
		(pad "2" smd rect
			(at -0.889 0 180)
			(size 1.016 1.27)
			(layers "B.Cu" "B.Mask" "B.Paste")
			(net "GND")
		)
	)
	(footprint ""
		(layer "B.Cu")
		(at 190.881 -97.119948 -90)
		(property "Reference" "R260"
			(at 0 0 90)
			(layer "B.SilkS")
			(hide yes)
			(effects
				(font
					(size 1.27 1.27)
				)
				(justify mirror)
			)
		)
		(property "Value" ""
			(at 0 0 90)
			(layer "B.Fab")
			(effects
				(font
					(size 1.27 1.27)
				)
				(justify mirror)
			)
		)
		(duplicate_pad_numbers_are_jumpers no)
		(fp_line
			(start -0.7874 0.4064)
			(end 0.7874 0.4064)
			(stroke
				(width 0.1524)
				(type default)
			)
			(layer "B.SilkS")
		)
		(fp_line
			(start 0.7874 0.4064)
			(end 0.7874 -0.4064)
			(stroke
				(width 0.1524)
				(type default)
			)
			(layer "B.SilkS")
		)
		(fp_line
			(start -0.7874 -0.4064)
			(end -0.7874 0.4064)
			(stroke
				(width 0.1524)
				(type default)
			)
			(layer "B.SilkS")
		)
		(fp_line
			(start 0.7874 -0.4064)
			(end -0.7874 -0.4064)
			(stroke
				(width 0.1524)
				(type default)
			)
			(layer "B.SilkS")
		)
		(fp_line
			(start -0.67945 0.3048)
			(end -0.120396 0.3048)
			(stroke
				(width 0.1)
				(type default)
			)
			(layer "B.Fab")
		)
		(fp_line
			(start -0.120396 0.3048)
			(end -0.120396 0.2794)
			(stroke
				(width 0.1)
				(type default)
			)
			(layer "B.Fab")
		)
		(fp_line
			(start 0.12065 0.3048)
			(end 0.67945 0.3048)
			(stroke
				(width 0.1)
				(type default)
			)
			(layer "B.Fab")
		)
		(fp_line
			(start 0.67945 0.3048)
			(end 0.67945 -0.305054)
			(stroke
				(width 0.1)
				(type default)
			)
			(layer "B.Fab")
		)
		(fp_line
			(start -0.120396 0.2794)
			(end 0.12065 0.2794)
			(stroke
				(width 0.1)
				(type default)
			)
			(layer "B.Fab")
		)
		(fp_line
			(start 0.12065 0.2794)
			(end 0.12065 0.3048)
			(stroke
				(width 0.1)
				(type default)
			)
			(layer "B.Fab")
		)
		(fp_line
			(start -0.12065 -0.2794)
			(end -0.12065 -0.3048)
			(stroke
				(width 0.1)
				(type default)
			)
			(layer "B.Fab")
		)
		(fp_line
			(start 0.12065 -0.2794)
			(end -0.12065 -0.2794)
			(stroke
				(width 0.1)
				(type default)
			)
			(layer "B.Fab")
		)
		(fp_line
			(start -0.67945 -0.3048)
			(end -0.67945 0.3048)
			(stroke
				(width 0.1)
				(type default)
			)
			(layer "B.Fab")
		)
		(fp_line
			(start -0.12065 -0.3048)
			(end -0.67945 -0.3048)
			(stroke
				(width 0.1)
				(type default)
			)
			(layer "B.Fab")
		)
		(fp_line
			(start 0.12065 -0.305054)
			(end 0.12065 -0.2794)
			(stroke
				(width 0.1)
				(type default)
			)
			(layer "B.Fab")
		)
		(fp_line
			(start 0.67945 -0.305054)
			(end 0.12065 -0.305054)
			(stroke
				(width 0.1)
				(type default)
			)
			(layer "B.Fab")
		)
		(pad "1" smd circle
			(at 0.40005 0 90)
			(size 0 0)
			(layers "B.Cu" "B.Mask" "B.Paste")
			(net "CPU1_SP5R1")
		)
		(pad "2" smd circle
			(at -0.40005 0 90)
			(size 0 0)
			(layers "B.Cu" "B.Mask" "B.Paste")
			(net "FM_CPU1_SP5R1")
		)
	)
	(footprint ""
		(layer "B.Cu")
		(at 216.18448 -54.955948)
		(property "Reference" "C2069"
			(at 0 0 0)
			(layer "B.SilkS")
			(hide yes)
			(effects
				(font
					(size 1.27 1.27)
				)
				(justify mirror)
			)
		)
		(property "Value" ""
			(at 0 0 0)
			(layer "B.Fab")
			(effects
				(font
					(size 1.27 1.27)
				)
				(justify mirror)
			)
		)
		(duplicate_pad_numbers_are_jumpers no)
		(fp_line
			(start -0.7874 -0.4064)
			(end -0.7874 0.4064)
			(stroke
				(width 0.1524)
				(type default)
			)
			(layer "B.SilkS")
		)
		(fp_line
			(start -0.7874 0.4064)
			(end 0.7874 0.4064)
			(stroke
				(width 0.1524)
				(type default)
			)
			(layer "B.SilkS")
		)
		(fp_line
			(start 0.7874 -0.4064)
			(end -0.7874 -0.4064)
			(stroke
				(width 0.1524)
				(type default)
			)
			(layer "B.SilkS")
		)
		(fp_line
			(start 0.7874 0.4064)
			(end 0.7874 -0.4064)
			(stroke
				(width 0.1524)
				(type default)
			)
			(layer "B.SilkS")
		)
		(fp_line
			(start -0.67945 -0.3048)
			(end -0.67945 0.3048)
			(stroke
				(width 0.1)
				(type default)
			)
			(layer "B.Fab")
		)
		(fp_line
			(start -0.67945 0.3048)
			(end -0.120396 0.3048)
			(stroke
				(width 0.1)
				(type default)
			)
			(layer "B.Fab")
		)
		(fp_line
			(start -0.12065 -0.3048)
			(end -0.67945 -0.3048)
			(stroke
				(width 0.1)
				(type default)
			)
			(layer "B.Fab")
		)
		(fp_line
			(start -0.12065 -0.2794)
			(end -0.12065 -0.3048)
			(stroke
				(width 0.1)
				(type default)
			)
			(layer "B.Fab")
		)
		(fp_line
			(start -0.120396 0.2794)
			(end 0.12065 0.2794)
			(stroke
				(width 0.1)
				(type default)
			)
			(layer "B.Fab")
		)
		(fp_line
			(start -0.120396 0.3048)
			(end -0.120396 0.2794)
			(stroke
				(width 0.1)
				(type default)
			)
			(layer "B.Fab")
		)
		(fp_line
			(start 0.12065 -0.305054)
			(end 0.12065 -0.2794)
			(stroke
				(width 0.1)
				(type default)
			)
			(layer "B.Fab")
		)
		(fp_line
			(start 0.12065 -0.2794)
			(end -0.12065 -0.2794)
			(stroke
				(width 0.1)
				(type default)
			)
			(layer "B.Fab")
		)
		(fp_line
			(start 0.12065 0.2794)
			(end 0.12065 0.3048)
			(stroke
				(width 0.1)
				(type default)
			)
			(layer "B.Fab")
		)
		(fp_line
			(start 0.12065 0.3048)
			(end 0.67945 0.3048)
			(stroke
				(width 0.1)
				(type default)
			)
			(layer "B.Fab")
		)
		(fp_line
			(start 0.67945 -0.305054)
			(end 0.12065 -0.305054)
			(stroke
				(width 0.1)
				(type default)
			)
			(layer "B.Fab")
		)
		(fp_line
			(start 0.67945 0.3048)
			(end 0.67945 -0.305054)
			(stroke
				(width 0.1)
				(type default)
			)
			(layer "B.Fab")
		)
		(pad "1" smd circle
			(at 0.40005 0 180)
			(size 0 0)
			(layers "B.Cu" "B.Mask" "B.Paste")
			(net "P3V3_E1S_0_R")
		)
		(pad "2" smd circle
			(at -0.40005 0 180)
			(size 0 0)
			(layers "B.Cu" "B.Mask" "B.Paste")
			(net "GND")
		)
	)
	(footprint ""
		(layer "B.Cu")
		(at 304.023776 -193.99631)
		(property "Reference" "R89"
			(at 0 0 0)
			(layer "B.SilkS")
			(hide yes)
			(effects
				(font
					(size 1.27 1.27)
				)
				(justify mirror)
			)
		)
		(property "Value" ""
			(at 0 0 0)
			(layer "B.Fab")
			(effects
				(font
					(size 1.27 1.27)
				)
				(justify mirror)
			)
		)
		(duplicate_pad_numbers_are_jumpers no)
		(fp_line
			(start -0.7874 -0.4064)
			(end -0.7874 0.4064)
			(stroke
				(width 0.1524)
				(type default)
			)
			(layer "B.SilkS")
		)
		(fp_line
			(start -0.7874 0.4064)
			(end 0.7874 0.4064)
			(stroke
				(width 0.1524)
				(type default)
			)
			(layer "B.SilkS")
		)
		(fp_line
			(start 0.7874 -0.4064)
			(end -0.7874 -0.4064)
			(stroke
				(width 0.1524)
				(type default)
			)
			(layer "B.SilkS")
		)
		(fp_line
			(start 0.7874 0.4064)
			(end 0.7874 -0.4064)
			(stroke
				(width 0.1524)
				(type default)
			)
			(layer "B.SilkS")
		)
		(fp_line
			(start -0.67945 -0.3048)
			(end -0.67945 0.3048)
			(stroke
				(width 0.1)
				(type default)
			)
			(layer "B.Fab")
		)
		(fp_line
			(start -0.67945 0.3048)
			(end -0.120396 0.3048)
			(stroke
				(width 0.1)
				(type default)
			)
			(layer "B.Fab")
		)
		(fp_line
			(start -0.12065 -0.3048)
			(end -0.67945 -0.3048)
			(stroke
				(width 0.1)
				(type default)
			)
			(layer "B.Fab")
		)
		(fp_line
			(start -0.12065 -0.2794)
			(end -0.12065 -0.3048)
			(stroke
				(width 0.1)
				(type default)
			)
			(layer "B.Fab")
		)
		(fp_line
			(start -0.120396 0.2794)
			(end 0.12065 0.2794)
			(stroke
				(width 0.1)
				(type default)
			)
			(layer "B.Fab")
		)
		(fp_line
			(start -0.120396 0.3048)
			(end -0.120396 0.2794)
			(stroke
				(width 0.1)
				(type default)
			)
			(layer "B.Fab")
		)
		(fp_line
			(start 0.12065 -0.305054)
			(end 0.12065 -0.2794)
			(stroke
				(width 0.1)
				(type default)
			)
			(layer "B.Fab")
		)
		(fp_line
			(start 0.12065 -0.2794)
			(end -0.12065 -0.2794)
			(stroke
				(width 0.1)
				(type default)
			)
			(layer "B.Fab")
		)
		(fp_line
			(start 0.12065 0.2794)
			(end 0.12065 0.3048)
			(stroke
				(width 0.1)
				(type default)
			)
			(layer "B.Fab")
		)
		(fp_line
			(start 0.12065 0.3048)
			(end 0.67945 0.3048)
			(stroke
				(width 0.1)
				(type default)
			)
			(layer "B.Fab")
		)
		(fp_line
			(start 0.67945 -0.305054)
			(end 0.12065 -0.305054)
			(stroke
				(width 0.1)
				(type default)
			)
			(layer "B.Fab")
		)
		(fp_line
			(start 0.67945 0.3048)
			(end 0.67945 -0.305054)
			(stroke
				(width 0.1)
				(type default)
			)
			(layer "B.Fab")
		)
		(pad "1" smd circle
			(at 0.40005 0 180)
			(size 0 0)
			(layers "B.Cu" "B.Mask" "B.Paste")
			(net "P3V3")
		)
		(pad "2" smd circle
			(at -0.40005 0 180)
			(size 0 0)
			(layers "B.Cu" "B.Mask" "B.Paste")
			(net "PWRGD_CHA_CPU0_DIMM0")
		)
	)
	(footprint ""
		(layer "B.Cu")
		(at 440.333384 -16.014954)
		(property "Reference" "C34"
			(at 0 0 0)
			(layer "B.SilkS")
			(hide yes)
			(effects
				(font
					(size 1.27 1.27)
				)
				(justify mirror)
			)
		)
		(property "Value" ""
			(at 0 0 0)
			(layer "B.Fab")
			(effects
				(font
					(size 1.27 1.27)
				)
				(justify mirror)
			)
		)
		(duplicate_pad_numbers_are_jumpers no)
		(fp_line
			(start -1.524 -0.762)
			(end -1.524 0.762)
			(stroke
				(width 0.1524)
				(type default)
			)
			(layer "B.SilkS")
		)
		(fp_line
			(start -1.524 0.762)
			(end 1.524 0.762)
			(stroke
				(width 0.1524)
				(type default)
			)
			(layer "B.SilkS")
		)
		(fp_line
			(start 1.524 -0.762)
			(end -1.524 -0.762)
			(stroke
				(width 0.1524)
				(type default)
			)
			(layer "B.SilkS")
		)
		(fp_line
			(start 1.524 0.762)
			(end 1.524 -0.762)
			(stroke
				(width 0.1524)
				(type default)
			)
			(layer "B.SilkS")
		)
		(fp_line
			(start -1.1049 -0.724916)
			(end 1.1049 -0.724916)
			(stroke
				(width 0.1)
				(type default)
			)
			(layer "B.Fab")
		)
		(fp_line
			(start -1.1049 0.724916)
			(end -1.1049 -0.724916)
			(stroke
				(width 0.1)
				(type default)
			)
			(layer "B.Fab")
		)
		(fp_line
			(start 1.1049 -0.724916)
			(end 1.1049 0.724916)
			(stroke
				(width 0.1)
				(type default)
			)
			(layer "B.Fab")
		)
		(fp_line
			(start 1.1049 0.724916)
			(end -1.1049 0.724916)
			(stroke
				(width 0.1)
				(type default)
			)
			(layer "B.Fab")
		)
		(pad "1" smd rect
			(at 0.889 0)
			(size 1.016 1.27)
			(layers "B.Cu" "B.Mask" "B.Paste")
			(net "P12V_OCP_SFF_R")
		)
		(pad "2" smd rect
			(at -0.889 0)
			(size 1.016 1.27)
			(layers "B.Cu" "B.Mask" "B.Paste")
			(net "GND")
		)
	)
	(footprint ""
		(layer "B.Cu")
		(at 140.55852 -35.812222 -90)
		(property "Reference" "C6042"
			(at 0 0 90)
			(layer "B.SilkS")
			(hide yes)
			(effects
				(font
					(size 1.27 1.27)
				)
				(justify mirror)
			)
		)
		(property "Value" ""
			(at 0 0 90)
			(layer "B.Fab")
			(effects
				(font
					(size 1.27 1.27)
				)
				(justify mirror)
			)
		)
		(duplicate_pad_numbers_are_jumpers no)
		(fp_line
			(start -1.2954 0.5842)
			(end 1.2954 0.5842)
			(stroke
				(width 0.1524)
				(type default)
			)
			(layer "B.SilkS")
		)
		(fp_line
			(start 1.2954 0.5842)
			(end 1.2954 -0.5842)
			(stroke
				(width 0.1524)
				(type default)
			)
			(layer "B.SilkS")
		)
		(fp_line
			(start -1.2954 -0.5842)
			(end -1.2954 0.5842)
			(stroke
				(width 0.1524)
				(type default)
			)
			(layer "B.SilkS")
		)
		(fp_line
			(start 1.2954 -0.5842)
			(end -1.2954 -0.5842)
			(stroke
				(width 0.1524)
				(type default)
			)
			(layer "B.SilkS")
		)
		(fp_line
			(start -0.8636 0.4572)
			(end 0.8636 0.4572)
			(stroke
				(width 0.1)
				(type default)
			)
			(layer "B.Fab")
		)
		(fp_line
			(start 0.8636 0.4572)
			(end 0.8636 0.4064)
			(stroke
				(width 0.1)
				(type default)
			)
			(layer "B.Fab")
		)
		(fp_line
			(start -1.1938 0.4064)
			(end -0.8636 0.4064)
			(stroke
				(width 0.1)
				(type default)
			)
			(layer "B.Fab")
		)
		(fp_line
			(start -0.8636 0.4064)
			(end -0.8636 0.4572)
			(stroke
				(width 0.1)
				(type default)
			)
			(layer "B.Fab")
		)
		(fp_line
			(start 0.8636 0.4064)
			(end 1.1938 0.4064)
			(stroke
				(width 0.1)
				(type default)
			)
			(layer "B.Fab")
		)
		(fp_line
			(start 1.1938 0.4064)
			(end 1.1938 -0.4064)
			(stroke
				(width 0.1)
				(type default)
			)
			(layer "B.Fab")
		)
		(fp_line
			(start -1.1938 -0.4064)
			(end -1.1938 0.4064)
			(stroke
				(width 0.1)
				(type default)
			)
			(layer "B.Fab")
		)
		(fp_line
			(start -0.8636 -0.4064)
			(end -1.1938 -0.4064)
			(stroke
				(width 0.1)
				(type default)
			)
			(layer "B.Fab")
		)
		(fp_line
			(start 0.8636 -0.4064)
			(end 0.8636 -0.4572)
			(stroke
				(width 0.1)
				(type default)
			)
			(layer "B.Fab")
		)
		(fp_line
			(start 1.1938 -0.4064)
			(end 0.8636 -0.4064)
			(stroke
				(width 0.1)
				(type default)
			)
			(layer "B.Fab")
		)
		(fp_line
			(start -0.8636 -0.4572)
			(end -0.8636 -0.4064)
			(stroke
				(width 0.1)
				(type default)
			)
			(layer "B.Fab")
		)
		(fp_line
			(start 0.8636 -0.4572)
			(end -0.8636 -0.4572)
			(stroke
				(width 0.1)
				(type default)
			)
			(layer "B.Fab")
		)
		(pad "1" smd rect
			(at 0.7366 0 180)
			(size 0.7112 0.8128)
			(layers "B.Cu" "B.Mask" "B.Paste")
			(net "P3V3_AUX_CPU0_USB_AVDD33")
		)
		(pad "2" smd rect
			(at -0.7366 0 180)
			(size 0.7112 0.8128)
			(layers "B.Cu" "B.Mask" "B.Paste")
			(net "GND")
		)
	)
)
